(kicad_pcb
	(version 20241229)
	(generator "pcbnew")
	(generator_version "9.0")
	(general
		(thickness 1.6296)
		(legacy_teardrops no)
	)
	(paper "A3")
	(title_block
		(title "Thunderbolt to 10GbE adapter")
		(date "2026-04-21")
		(rev "1.1.0")
		(company "Antmicro Ltd")
		(comment 1 "www.antmicro.com")
		(comment 9 "footprints 506-510 of 703")
	)
	(layers
		(0 "F.Cu" signal)
		(4 "In1.Cu" signal)
		(6 "In2.Cu" signal)
		(8 "In3.Cu" signal)
		(10 "In4.Cu" signal)
		(12 "In5.Cu" signal)
		(14 "In6.Cu" signal)
		(2 "B.Cu" signal)
		(9 "F.Adhes" user "F.Adhesive")
		(11 "B.Adhes" user "B.Adhesive")
		(13 "F.Paste" user)
		(15 "B.Paste" user)
		(5 "F.SilkS" user "F.Silkscreen")
		(7 "B.SilkS" user "B.Silkscreen")
		(1 "F.Mask" user)
		(3 "B.Mask" user)
		(17 "Dwgs.User" user "User.Drawings")
		(19 "Cmts.User" user "User.Comments")
		(21 "Eco1.User" user "User.Eco1")
		(23 "Eco2.User" user "User.Eco2")
		(25 "Edge.Cuts" user)
		(27 "Margin" user)
		(31 "F.CrtYd" user "F.Courtyard")
		(29 "B.CrtYd" user "B.Courtyard")
		(35 "F.Fab" user)
		(33 "B.Fab" user)
	)
	(footprint "antmicro-footprints:C_0402_1005Metric"
		(layer "B.Cu")
		(at 149.331865 79.260116 180)
		(descr "Capacitor SMD 0402")
		(tags "capacitor SMD 0402")
		(property "Reference" "C218"
			(at -19.468135 -9.464883 0)
			(layer "B.SilkS")
			(effects
				(font
					(size 0.7 0.7)
					(thickness 0.15)
				)
				(justify mirror)
			)
		)
		(property "Value" "C_1u_25V_0402"
			(at -1.022927 -2.155213 0)
			(layer "B.Fab")
			(effects
				(font
					(size 0.7 0.7)
					(thickness 0.15)
				)
				(justify left bottom mirror)
			)
		)
		(property "Datasheet" "https://www.murata.com/products/productdetail?partno=GRM155R61E105KE11%23"
			(at 0 0 0)
			(layer "B.Fab")
			(hide yes)
			(effects
				(font
					(size 1.27 1.27)
					(thickness 0.15)
				)
				(justify mirror)
			)
		)
		(property "Description" "SMD Multilayer Ceramic Capacitor, 1 µF, 25 V, 0402 [1005 Metric], ± 10%, X5R, GRM Series"
			(at 0 0 0)
			(layer "B.Fab")
			(hide yes)
			(effects
				(font
					(size 1.27 1.27)
					(thickness 0.15)
				)
				(justify mirror)
			)
		)
		(property "MPN" "GRM155R61E105KE11J"
			(at 0 0 180)
			(unlocked yes)
			(layer "B.Fab")
			(hide yes)
			(effects
				(font
					(size 1 1)
					(thickness 0.15)
				)
				(justify mirror)
			)
		)
		(property "Manufacturer" "Murata"
			(at 0 0 180)
			(unlocked yes)
			(layer "B.Fab")
			(hide yes)
			(effects
				(font
					(size 1 1)
					(thickness 0.15)
				)
				(justify mirror)
			)
		)
		(property "License" "Apache-2.0"
			(at 0 0 180)
			(unlocked yes)
			(layer "B.Fab")
			(hide yes)
			(effects
				(font
					(size 1 1)
					(thickness 0.15)
				)
				(justify mirror)
			)
		)
		(property "Author" "Antmicro"
			(at 0 0 180)
			(unlocked yes)
			(layer "B.Fab")
			(hide yes)
			(effects
				(font
					(size 1 1)
					(thickness 0.15)
				)
				(justify mirror)
			)
		)
		(property "Val" "1u"
			(at 0 0 180)
			(unlocked yes)
			(layer "B.Fab")
			(hide yes)
			(effects
				(font
					(size 1 1)
					(thickness 0.15)
				)
				(justify mirror)
			)
		)
		(property "Voltage" "25V"
			(at 0 0 180)
			(unlocked yes)
			(layer "B.Fab")
			(hide yes)
			(effects
				(font
					(size 1 1)
					(thickness 0.15)
				)
				(justify mirror)
			)
		)
		(property "Dielectric" "X5R"
			(at 0 0 180)
			(unlocked yes)
			(layer "B.Fab")
			(hide yes)
			(effects
				(font
					(size 1 1)
					(thickness 0.15)
				)
				(justify mirror)
			)
		)
		(sheetname "/X710-AT2 power/")
		(sheetfile "x710-at2-power.kicad_sch")
		(attr smd)
		(fp_rect
			(start -0.925 0.47)
			(end 0.925 -0.47)
			(stroke
				(width 0.05)
				(type default)
			)
			(fill no)
			(layer "B.CrtYd")
		)
		(fp_line
			(start 0.504 0.25)
			(end 0.504 -0.248)
			(stroke
				(width 0.15)
				(type solid)
			)
			(layer "B.Fab")
		)
		(fp_line
			(start 0.504 -0.248)
			(end -0.494 -0.248)
			(stroke
				(width 0.15)
				(type solid)
			)
			(layer "B.Fab")
		)
		(fp_line
			(start -0.494 0.25)
			(end 0.504 0.25)
			(stroke
				(width 0.15)
				(type solid)
			)
			(layer "B.Fab")
		)
		(fp_line
			(start -0.494 -0.248)
			(end -0.494 0.25)
			(stroke
				(width 0.15)
				(type solid)
			)
			(layer "B.Fab")
		)
		(fp_text user "Author: Antmicro"
			(at -0.939 -3.399 0)
			(layer "B.Fab")
			(effects
				(font
					(size 0.7 0.7)
					(thickness 0.15)
				)
				(justify left bottom mirror)
			)
		)
		(fp_text user "License: Apache-2.0"
			(at -0.939 -5.799 0)
			(layer "B.Fab")
			(effects
				(font
					(size 0.7 0.7)
					(thickness 0.15)
				)
				(justify left bottom mirror)
			)
		)
		(fp_text user "${REFERENCE}"
			(at -0.939 -4.599 0)
			(layer "B.Fab")
			(effects
				(font
					(size 0.7 0.7)
					(thickness 0.15)
				)
				(justify left bottom mirror)
			)
		)
		(pad "1" smd roundrect
			(at -0.48 0 180)
			(size 0.59 0.64)
			(layers "B.Cu" "B.Mask" "B.Paste")
			(roundrect_rratio 0.25)
			(net 23 "GND")
			(pintype "passive")
		)
		(pad "2" smd roundrect
			(at 0.48 0 180)
			(size 0.59 0.64)
			(layers "B.Cu" "B.Mask" "B.Paste")
			(roundrect_rratio 0.25)
			(net 9 "VCCD")
			(pintype "passive")
		)
	)
	(footprint "antmicro-footprints:C_0402_1005Metric"
		(layer "B.Cu")
		(at 135.850001 133.1 90)
		(descr "Capacitor SMD 0402")
		(tags "capacitor SMD 0402")
		(property "Reference" "C22"
			(at 8.339997 19.525001 270)
			(layer "B.SilkS")
			(effects
				(font
					(size 0.7 0.7)
					(thickness 0.15)
				)
				(justify mirror)
			)
		)
		(property "Value" "C_2u2_0402"
			(at -1.022927 -2.155213 270)
			(layer "B.Fab")
			(effects
				(font
					(size 0.7 0.7)
					(thickness 0.15)
				)
				(justify left bottom mirror)
			)
		)
		(property "Datasheet" "https://product.tdk.com/en/search/capacitor/ceramic/mlcc/info?part_no=C1005X5R1A225K050BC"
			(at 0 0 270)
			(layer "B.Fab")
			(hide yes)
			(effects
				(font
					(size 1.27 1.27)
					(thickness 0.15)
				)
				(justify mirror)
			)
		)
		(property "Description" "SMD Multilayer Ceramic Capacitor, 2.2 µF, 10 V, 0402 [1005 Metric], ± 10%, X5R, C"
			(at 0 0 270)
			(layer "B.Fab")
			(hide yes)
			(effects
				(font
					(size 1.27 1.27)
					(thickness 0.15)
				)
				(justify mirror)
			)
		)
		(property "MPN" "C1005X5R1A225K050BC"
			(at 0 0 90)
			(unlocked yes)
			(layer "B.Fab")
			(hide yes)
			(effects
				(font
					(size 1 1)
					(thickness 0.15)
				)
				(justify mirror)
			)
		)
		(property "Manufacturer" "TDK"
			(at 0 0 90)
			(unlocked yes)
			(layer "B.Fab")
			(hide yes)
			(effects
				(font
					(size 1 1)
					(thickness 0.15)
				)
				(justify mirror)
			)
		)
		(property "License" "Apache-2.0"
			(at 0 0 90)
			(unlocked yes)
			(layer "B.Fab")
			(hide yes)
			(effects
				(font
					(size 1 1)
					(thickness 0.15)
				)
				(justify mirror)
			)
		)
		(property "Val" "2u2"
			(at 0 0 90)
			(unlocked yes)
			(layer "B.Fab")
			(hide yes)
			(effects
				(font
					(size 1 1)
					(thickness 0.15)
				)
				(justify mirror)
			)
		)
		(property "Voltage" ""
			(at 0 0 90)
			(unlocked yes)
			(layer "B.Fab")
			(hide yes)
			(effects
				(font
					(size 1 1)
					(thickness 0.15)
				)
				(justify mirror)
			)
		)
		(property "Dielectric" ""
			(at 0 0 90)
			(unlocked yes)
			(layer "B.Fab")
			(hide yes)
			(effects
				(font
					(size 1 1)
					(thickness 0.15)
				)
				(justify mirror)
			)
		)
		(property "Author" "Antmicro"
			(at 0 0 90)
			(unlocked yes)
			(layer "B.Fab")
			(hide yes)
			(effects
				(font
					(size 1 1)
					(thickness 0.15)
				)
				(justify mirror)
			)
		)
		(sheetname "/PD and TB DC-DC/")
		(sheetfile "PD_and_TB_DC_DC.kicad_sch")
		(attr smd)
		(fp_rect
			(start -0.925 0.47)
			(end 0.925 -0.47)
			(stroke
				(width 0.05)
				(type default)
			)
			(fill no)
			(layer "B.CrtYd")
		)
		(fp_line
			(start 0.504 -0.248)
			(end -0.494 -0.248)
			(stroke
				(width 0.15)
				(type solid)
			)
			(layer "B.Fab")
		)
		(fp_line
			(start -0.494 -0.248)
			(end -0.494 0.25)
			(stroke
				(width 0.15)
				(type solid)
			)
			(layer "B.Fab")
		)
		(fp_line
			(start 0.504 0.25)
			(end 0.504 -0.248)
			(stroke
				(width 0.15)
				(type solid)
			)
			(layer "B.Fab")
		)
		(fp_line
			(start -0.494 0.25)
			(end 0.504 0.25)
			(stroke
				(width 0.15)
				(type solid)
			)
			(layer "B.Fab")
		)
		(fp_text user "License: Apache-2.0"
			(at -0.939 -5.799 270)
			(layer "B.Fab")
			(effects
				(font
					(size 0.7 0.7)
					(thickness 0.15)
				)
				(justify left bottom mirror)
			)
		)
		(fp_text user "${REFERENCE}"
			(at -0.939 -4.599 270)
			(layer "B.Fab")
			(effects
				(font
					(size 0.7 0.7)
					(thickness 0.15)
				)
				(justify left bottom mirror)
			)
		)
		(fp_text user "Author: Antmicro"
			(at -0.939 -3.399 270)
			(layer "B.Fab")
			(effects
				(font
					(size 0.7 0.7)
					(thickness 0.15)
				)
				(justify left bottom mirror)
			)
		)
		(pad "1" smd roundrect
			(at -0.48 0 90)
			(size 0.59 0.64)
			(layers "B.Cu" "B.Mask" "B.Paste")
			(roundrect_rratio 0.25)
			(net 176 "Net-(U3-LDO_BMC)")
			(pintype "passive")
		)
		(pad "2" smd roundrect
			(at 0.48 0 90)
			(size 0.59 0.64)
			(layers "B.Cu" "B.Mask" "B.Paste")
			(roundrect_rratio 0.25)
			(net 23 "GND")
			(pintype "passive")
		)
	)
	(footprint "antmicro-footprints:SOT-416"
		(layer "B.Cu")
		(at 178.5 70.5 -90)
		(descr "SOT-416")
		(tags "SOT-416")
		(property "Reference" "Q3"
			(at -0.75 1.3 90)
			(layer "B.SilkS")
			(effects
				(font
					(size 0.7 0.7)
					(thickness 0.15)
				)
				(justify left bottom mirror)
			)
		)
		(property "Value" "DTC014T_SOT-416"
			(at 0 -2 90)
			(layer "B.Fab")
			(effects
				(font
					(size 0.7 0.7)
					(thickness 0.15)
				)
				(justify left bottom mirror)
			)
		)
		(property "Datasheet" "https://www.rohm.com/datasheet?p=DTC014TEB&dist=Mouser&media=referral&source=mouser.com&campaign=Mouser"
			(at 0 0 90)
			(layer "B.Fab")
			(hide yes)
			(effects
				(font
					(size 1.27 1.27)
					(thickness 0.15)
				)
				(justify mirror)
			)
		)
		(property "Description" "Bipolar (BJT) Single Transistor with built-in base resistor, NPN, 50V, 100mA, 150mW, SOT-416FL, Surface Mount"
			(at 0 0 90)
			(layer "B.Fab")
			(hide yes)
			(effects
				(font
					(size 1.27 1.27)
					(thickness 0.15)
				)
				(justify mirror)
			)
		)
		(property "Manufacturer" "ROHM Semiconductor"
			(at 0 0 270)
			(unlocked yes)
			(layer "B.Fab")
			(hide yes)
			(effects
				(font
					(size 1 1)
					(thickness 0.15)
				)
				(justify mirror)
			)
		)
		(property "MPN" "DTC014TEBTL"
			(at 0 0 270)
			(unlocked yes)
			(layer "B.Fab")
			(hide yes)
			(effects
				(font
					(size 1 1)
					(thickness 0.15)
				)
				(justify mirror)
			)
		)
		(property "Author" "Antmicro"
			(at 0 0 270)
			(unlocked yes)
			(layer "B.Fab")
			(hide yes)
			(effects
				(font
					(size 1 1)
					(thickness 0.15)
				)
				(justify mirror)
			)
		)
		(property "License" "Apache-2.0"
			(at 0 0 270)
			(unlocked yes)
			(layer "B.Fab")
			(hide yes)
			(effects
				(font
					(size 1 1)
					(thickness 0.15)
				)
				(justify mirror)
			)
		)
		(sheetname "/X710 DCDC converters/")
		(sheetfile "DCDC_converters_X710.kicad_sch")
		(attr smd)
		(fp_line
			(start 0.508 0.9)
			(end -0.5 0.9)
			(stroke
				(width 0.15)
				(type solid)
			)
			(layer "B.SilkS")
		)
		(fp_line
			(start 0.508 0.9)
			(end 0.508 0.592)
			(stroke
				(width 0.15)
				(type solid)
			)
			(layer "B.SilkS")
		)
		(fp_line
			(start -0.5 0.15)
			(end -0.5 -0.15)
			(stroke
				(width 0.15)
				(type solid)
			)
			(layer "B.SilkS")
		)
		(fp_line
			(start 0.5 -0.9)
			(end 0.5 -0.7)
			(stroke
				(width 0.15)
				(type solid)
			)
			(layer "B.SilkS")
		)
		(fp_line
			(start 0.5 -0.9)
			(end -0.5 -0.9)
			(stroke
				(width 0.15)
				(type solid)
			)
			(layer "B.SilkS")
		)
		(fp_rect
			(start -1 1.05)
			(end 1 -1.05)
			(stroke
				(width 0.05)
				(type solid)
			)
			(fill no)
			(layer "B.CrtYd")
		)
		(fp_line
			(start -0.05 0.9)
			(end -0.45 0.5)
			(stroke
				(width 0.15)
				(type solid)
			)
			(layer "B.Fab")
		)
		(fp_rect
			(start 0.45 -0.9)
			(end -0.45 0.9)
			(stroke
				(width 0.15)
				(type solid)
			)
			(fill no)
			(layer "B.Fab")
		)
		(fp_text user "${REFERENCE}"
			(at -1 -3.4 90)
			(layer "B.Fab")
			(effects
				(font
					(size 0.7 0.7)
					(thickness 0.15)
				)
				(justify left bottom mirror)
			)
		)
		(fp_text user "License: Apache-2.0"
			(at -1 -5.802 90)
			(layer "B.Fab")
			(effects
				(font
					(size 0.7 0.7)
					(thickness 0.15)
				)
				(justify left bottom mirror)
			)
		)
		(fp_text user "Author: Antmicro"
			(at -1 -4.602 90)
			(layer "B.Fab")
			(effects
				(font
					(size 0.7 0.7)
					(thickness 0.15)
				)
				(justify left bottom mirror)
			)
		)
		(pad "1" smd rect
			(at -0.652 0.5 270)
			(size 0.6 0.5)
			(layers "B.Cu" "B.Mask" "B.Paste")
			(net 338 "/X710 DCDC converters/+1V88_OUT")
			(pinfunction "B")
			(pintype "input")
		)
		(pad "2" smd rect
			(at -0.652 -0.498 270)
			(size 0.6 0.5)
			(layers "B.Cu" "B.Mask" "B.Paste")
			(net 23 "GND")
			(pinfunction "E")
			(pintype "passive")
		)
		(pad "3" smd rect
			(at 0.65 0 270)
			(size 0.6 0.5)
			(layers "B.Cu" "B.Mask" "B.Paste")
			(net 429 "Net-(Q3-C)")
			(pinfunction "C")
			(pintype "passive")
		)
	)
	(footprint "antmicro-footprints:R_0402_1005Metric"
		(layer "B.Cu")
		(at 140.4 135.600001 180)
		(descr "Resistor SMD 0402")
		(tags "resistor SMD 0402")
		(property "Reference" "R13"
			(at -19.525001 8.1 0)
			(layer "B.SilkS")
			(effects
				(font
					(size 0.7 0.7)
					(thickness 0.15)
				)
				(justify mirror)
			)
		)
		(property "Value" "R_3k3_0402"
			(at -1.011843 -1.772047 0)
			(layer "B.Fab")
			(effects
				(font
					(size 0.7 0.7)
					(thickness 0.15)
				)
				(justify left bottom mirror)
			)
		)
		(property "Datasheet" "https://www.bourns.com/docs/product-datasheets/cr.pdf"
			(at 0 0 0)
			(layer "B.Fab")
			(hide yes)
			(effects
				(font
					(size 1.27 1.27)
					(thickness 0.15)
				)
				(justify mirror)
			)
		)
		(property "Description" "SMD Chip Resistor, 3.3 kohm, ± 1%, 63 mW, 0402 [1005 Metric], Thick Film, General Purpose"
			(at 0 0 0)
			(layer "B.Fab")
			(hide yes)
			(effects
				(font
					(size 1.27 1.27)
					(thickness 0.15)
				)
				(justify mirror)
			)
		)
		(property "MPN" "CR0402-FX-3301GLF"
			(at 0 0 180)
			(unlocked yes)
			(layer "B.Fab")
			(hide yes)
			(effects
				(font
					(size 1 1)
					(thickness 0.15)
				)
				(justify mirror)
			)
		)
		(property "Manufacturer" "Bourns"
			(at 0 0 180)
			(unlocked yes)
			(layer "B.Fab")
			(hide yes)
			(effects
				(font
					(size 1 1)
					(thickness 0.15)
				)
				(justify mirror)
			)
		)
		(property "License" "Apache-2.0"
			(at 0 0 180)
			(unlocked yes)
			(layer "B.Fab")
			(hide yes)
			(effects
				(font
					(size 1 1)
					(thickness 0.15)
				)
				(justify mirror)
			)
		)
		(property "Val" "3k3"
			(at 0 0 180)
			(unlocked yes)
			(layer "B.Fab")
			(hide yes)
			(effects
				(font
					(size 1 1)
					(thickness 0.15)
				)
				(justify mirror)
			)
		)
		(property "Tolerance" "1%"
			(at 0 0 180)
			(unlocked yes)
			(layer "B.Fab")
			(hide yes)
			(effects
				(font
					(size 1 1)
					(thickness 0.15)
				)
				(justify mirror)
			)
		)
		(property "Author" "Antmicro"
			(at 0 0 180)
			(unlocked yes)
			(layer "B.Fab")
			(hide yes)
			(effects
				(font
					(size 1 1)
					(thickness 0.15)
				)
				(justify mirror)
			)
		)
		(sheetname "/PD and TB DC-DC/")
		(sheetfile "PD_and_TB_DC_DC.kicad_sch")
		(attr smd)
		(fp_rect
			(start -0.925 0.47)
			(end 0.925 -0.47)
			(stroke
				(width 0.05)
				(type default)
			)
			(fill no)
			(layer "B.CrtYd")
		)
		(fp_rect
			(start -0.5 0.25)
			(end 0.5 -0.25)
			(stroke
				(width 0.15)
				(type solid)
			)
			(fill no)
			(layer "B.Fab")
		)
		(fp_text user "${REFERENCE}"
			(at -0.95 -3.168 0)
			(layer "B.Fab")
			(effects
				(font
					(size 0.7 0.7)
					(thickness 0.15)
				)
				(justify left bottom mirror)
			)
		)
		(fp_text user "Author: Antmicro"
			(at -0.95 -4.169 0)
			(layer "B.Fab")
			(effects
				(font
					(size 0.7 0.7)
					(thickness 0.15)
				)
				(justify left bottom mirror)
			)
		)
		(fp_text user "License: Apache-2.0"
			(at -0.95 -5.169 0)
			(layer "B.Fab")
			(effects
				(font
					(size 0.7 0.7)
					(thickness 0.15)
				)
				(justify left bottom mirror)
			)
		)
		(pad "1" smd roundrect
			(at -0.48 0 180)
			(size 0.59 0.64)
			(layers "B.Cu" "B.Mask" "B.Paste")
			(roundrect_rratio 0.25)
			(net 304 "/PD and TB DC-DC/TPS_3V3")
			(pintype "passive")
		)
		(pad "2" smd roundrect
			(at 0.48 0 180)
			(size 0.59 0.64)
			(layers "B.Cu" "B.Mask" "B.Paste")
			(roundrect_rratio 0.25)
			(net 199 "Net-(U3-I2C_SCL2)")
			(pintype "passive")
		)
	)
	(footprint "antmicro-footprints:R_0402_1005Metric"
		(layer "B.Cu")
		(at 156.131866 70.035117 -90)
		(descr "Resistor SMD 0402")
		(tags "resistor SMD 0402")
		(property "Reference" "R169"
			(at 9.464883 -19.468134 90)
			(layer "B.SilkS")
			(effects
				(font
					(size 0.7 0.7)
					(thickness 0.15)
				)
				(justify mirror)
			)
		)
		(property "Value" "R_22R_0402"
			(at -1.011843 -1.772047 90)
			(layer "B.Fab")
			(effects
				(font
					(size 0.7 0.7)
					(thickness 0.15)
				)
				(justify left bottom mirror)
			)
		)
		(property "Datasheet" "https://www.bourns.com/docs/product-datasheets/cr.pdf"
			(at 0 0 90)
			(layer "B.Fab")
			(hide yes)
			(effects
				(font
					(size 1.27 1.27)
					(thickness 0.15)
				)
				(justify mirror)
			)
		)
		(property "Description" "SMD Chip Resistor, 22 ohm, ± 1%, 62.5 mW, 0402 [1005 Metric], Thick Film, General Purpose"
			(at 0 0 90)
			(layer "B.Fab")
			(hide yes)
			(effects
				(font
					(size 1.27 1.27)
					(thickness 0.15)
				)
				(justify mirror)
			)
		)
		(property "MPN" "CR0402-FX-22R0GLF"
			(at 0 0 270)
			(unlocked yes)
			(layer "B.Fab")
			(hide yes)
			(effects
				(font
					(size 1 1)
					(thickness 0.15)
				)
				(justify mirror)
			)
		)
		(property "Manufacturer" "Bourns"
			(at 0 0 270)
			(unlocked yes)
			(layer "B.Fab")
			(hide yes)
			(effects
				(font
					(size 1 1)
					(thickness 0.15)
				)
				(justify mirror)
			)
		)
		(property "License" "Apache-2.0"
			(at 0 0 270)
			(unlocked yes)
			(layer "B.Fab")
			(hide yes)
			(effects
				(font
					(size 1 1)
					(thickness 0.15)
				)
				(justify mirror)
			)
		)
		(property "Author" "Antmicro"
			(at 0 0 270)
			(unlocked yes)
			(layer "B.Fab")
			(hide yes)
			(effects
				(font
					(size 1 1)
					(thickness 0.15)
				)
				(justify mirror)
			)
		)
		(property "Val" "22R"
			(at 0 0 270)
			(unlocked yes)
			(layer "B.Fab")
			(hide yes)
			(effects
				(font
					(size 1 1)
					(thickness 0.15)
				)
				(justify mirror)
			)
		)
		(property "Tolerance" "1%"
			(at 0 0 270)
			(unlocked yes)
			(layer "B.Fab")
			(hide yes)
			(effects
				(font
					(size 1 1)
					(thickness 0.15)
				)
				(justify mirror)
			)
		)
		(sheetname "/X710-AT2 Misc/")
		(sheetfile "x710-at2-mics.kicad_sch")
		(attr smd)
		(fp_rect
			(start -0.925 0.47)
			(end 0.925 -0.47)
			(stroke
				(width 0.05)
				(type default)
			)
			(fill no)
			(layer "B.CrtYd")
		)
		(fp_rect
			(start -0.5 0.25)
			(end 0.5 -0.25)
			(stroke
				(width 0.15)
				(type solid)
			)
			(fill no)
			(layer "B.Fab")
		)
		(fp_text user "Author: Antmicro"
			(at -0.95 -4.169 90)
			(layer "B.Fab")
			(effects
				(font
					(size 0.7 0.7)
					(thickness 0.15)
				)
				(justify left bottom mirror)
			)
		)
		(fp_text user "${REFERENCE}"
			(at -0.95 -3.168 90)
			(layer "B.Fab")
			(effects
				(font
					(size 0.7 0.7)
					(thickness 0.15)
				)
				(justify left bottom mirror)
			)
		)
		(fp_text user "License: Apache-2.0"
			(at -0.95 -5.169 90)
			(layer "B.Fab")
			(effects
				(font
					(size 0.7 0.7)
					(thickness 0.15)
				)
				(justify left bottom mirror)
			)
		)
		(pad "1" smd roundrect
			(at -0.48 0 270)
			(size 0.59 0.64)
			(layers "B.Cu" "B.Mask" "B.Paste")
			(roundrect_rratio 0.25)
			(net 137 "/X710-AT2 Misc/NCSI.RXD_1")
			(pintype "passive")
		)
		(pad "2" smd roundrect
			(at 0.48 0 270)
			(size 0.59 0.64)
			(layers "B.Cu" "B.Mask" "B.Paste")
			(roundrect_rratio 0.25)
			(net 443 "Net-(U14D-NCSI_RXD_1)")
			(pintype "passive")
		)
	)
)
